# S9S_MB_2U (Grand Teton) — schematic netlist excerpt (pin names and nets, part order shuffled) for the footprints in the layout excerpt that follows; sources: Cadence DE-HDL packaged netlist, KiCad conversion of 03242023_DA0F0TMBIJ0_F0T_Motherboard_J_brd_V01_OCP.brd

R3602  Q_RES  10 1% CHIP  pkg 0402LF  page 171 : A = P3V3_OCP_SFF_R ; B = VSENSE_P3V3_INA230_1_INP
PC2210  Q_CAP  1UF 25V 10% X6S  pkg C0402  page 192 : A = P3V3_E1S_VCC_0 ; B = GND

(kicad_pcb
	(version 20260206)
	(generator "pcbnew")
	(generator_version "10.0")
	(general
		(thickness 1.6)
		(legacy_teardrops no)
	)
	(paper "A4")
	(title_block
		(title "03242023_DA0F0TMBIJ0_F0T_Motherboard_J_brd_V01_OCP.brd")
		(comment 1 "Grand Teton / footprints 3934-3935 of 6105")
	)
	(layers
		(0 "F.Cu" signal "TOP")
		(4 "In1.Cu" signal "GND")
		(6 "In2.Cu" signal "IN1")
		(8 "In3.Cu" signal "GND1")
		(10 "In4.Cu" signal "IN2")
		(12 "In5.Cu" signal "GND2")
		(14 "In6.Cu" signal "IN3")
		(16 "In7.Cu" signal "GND3")
		(18 "In8.Cu" signal "VCC")
		(20 "In9.Cu" signal "VCC1")
		(22 "In10.Cu" signal "GND4")
		(24 "In11.Cu" signal "IN4")
		(26 "In12.Cu" signal "GND5")
		(28 "In13.Cu" signal "IN5")
		(30 "In14.Cu" signal "GND6")
		(32 "In15.Cu" signal "IN6")
		(34 "In16.Cu" signal "GND7")
		(2 "B.Cu" signal "BOTTOM")
		(9 "F.Adhes" user "F.Adhesive")
		(11 "B.Adhes" user "B.Adhesive")
		(13 "F.Paste" user "Package Geometry/Pastemask Top")
		(15 "B.Paste" user "Package Geometry/Pastemask Bottom")
		(5 "F.SilkS" user "Ref Des/Silkscreen Top")
		(7 "B.SilkS" user "Ref Des/Silkscreen Bottom")
		(1 "F.Mask" user "Board Geometry/Soldermask Top")
		(3 "B.Mask" user "Board Geometry/Soldermask Bottom")
		(17 "Dwgs.User" user "User.Drawings")
		(19 "Cmts.User" user "User.Comments")
		(21 "Eco1.User" user "User.Eco1")
		(23 "Eco2.User" user "User.Eco2")
		(25 "Edge.Cuts" user "Board Geometry/Outline")
		(27 "Margin" user)
		(31 "F.CrtYd" user "Package Geometry/Place Bound Top")
		(29 "B.CrtYd" user "Package Geometry/Place Bound Bottom")
		(35 "F.Fab" user "Ref Des/Assembly Top")
		(33 "B.Fab" user "Ref Des/Assembly Bottom")
	)
	(footprint ""
		(layer "F.Cu")
		(at 432.636676 -93.922342)
		(property "Reference" "R3602"
			(at 0 0 0)
			(layer "F.SilkS")
			(hide yes)
			(effects
				(font
					(size 1.27 1.27)
				)
			)
		)
		(property "Value" ""
			(at 0 0 0)
			(layer "F.Fab")
			(effects
				(font
					(size 1.27 1.27)
				)
			)
		)
		(duplicate_pad_numbers_are_jumpers no)
		(fp_line
			(start -0.7874 -0.4064)
			(end 0.7874 -0.4064)
			(stroke
				(width 0.1524)
				(type default)
			)
			(layer "F.SilkS")
		)
		(fp_line
			(start -0.7874 0.4064)
			(end -0.7874 -0.4064)
			(stroke
				(width 0.1524)
				(type default)
			)
			(layer "F.SilkS")
		)
		(fp_line
			(start 0.7874 -0.4064)
			(end 0.7874 0.4064)
			(stroke
				(width 0.1524)
				(type default)
			)
			(layer "F.SilkS")
		)
		(fp_line
			(start 0.7874 0.4064)
			(end -0.7874 0.4064)
			(stroke
				(width 0.1524)
				(type default)
			)
			(layer "F.SilkS")
		)
		(fp_line
			(start -0.67945 -0.305054)
			(end -0.12065 -0.305054)
			(stroke
				(width 0.1)
				(type default)
			)
			(layer "F.Fab")
		)
		(fp_line
			(start -0.67945 0.3048)
			(end -0.67945 -0.305054)
			(stroke
				(width 0.1)
				(type default)
			)
			(layer "F.Fab")
		)
		(fp_line
			(start -0.12065 -0.305054)
			(end -0.12065 -0.2794)
			(stroke
				(width 0.1)
				(type default)
			)
			(layer "F.Fab")
		)
		(fp_line
			(start -0.12065 -0.2794)
			(end 0.12065 -0.2794)
			(stroke
				(width 0.1)
				(type default)
			)
			(layer "F.Fab")
		)
		(fp_line
			(start -0.12065 0.2794)
			(end -0.12065 0.3048)
			(stroke
				(width 0.1)
				(type default)
			)
			(layer "F.Fab")
		)
		(fp_line
			(start -0.12065 0.3048)
			(end -0.67945 0.3048)
			(stroke
				(width 0.1)
				(type default)
			)
			(layer "F.Fab")
		)
		(fp_line
			(start 0.120396 0.2794)
			(end -0.12065 0.2794)
			(stroke
				(width 0.1)
				(type default)
			)
			(layer "F.Fab")
		)
		(fp_line
			(start 0.120396 0.3048)
			(end 0.120396 0.2794)
			(stroke
				(width 0.1)
				(type default)
			)
			(layer "F.Fab")
		)
		(fp_line
			(start 0.12065 -0.3048)
			(end 0.67945 -0.3048)
			(stroke
				(width 0.1)
				(type default)
			)
			(layer "F.Fab")
		)
		(fp_line
			(start 0.12065 -0.2794)
			(end 0.12065 -0.3048)
			(stroke
				(width 0.1)
				(type default)
			)
			(layer "F.Fab")
		)
		(fp_line
			(start 0.67945 -0.3048)
			(end 0.67945 0.3048)
			(stroke
				(width 0.1)
				(type default)
			)
			(layer "F.Fab")
		)
		(fp_line
			(start 0.67945 0.3048)
			(end 0.120396 0.3048)
			(stroke
				(width 0.1)
				(type default)
			)
			(layer "F.Fab")
		)
		(pad "1" smd circle
			(at -0.40005 0)
			(size 0 0)
			(layers "F.Cu" "F.Mask" "F.Paste")
			(net "P3V3_OCP_SFF_R")
		)
		(pad "2" smd circle
			(at 0.40005 0)
			(size 0 0)
			(layers "F.Cu" "F.Mask" "F.Paste")
			(net "VSENSE_P3V3_INA230_1_INP")
		)
	)
	(footprint ""
		(layer "F.Cu")
		(at 219.974922 -73.484994 180)
		(property "Reference" "PC2210"
			(at 0 0 180)
			(layer "F.SilkS")
			(hide yes)
			(effects
				(font
					(size 1.27 1.27)
				)
			)
		)
		(property "Value" ""
			(at 0 0 180)
			(layer "F.Fab")
			(effects
				(font
					(size 1.27 1.27)
				)
			)
		)
		(duplicate_pad_numbers_are_jumpers no)
		(fp_line
			(start 0.7874 0.4064)
			(end -0.7874 0.4064)
			(stroke
				(width 0.1524)
				(type default)
			)
			(layer "F.SilkS")
		)
		(fp_line
			(start 0.7874 -0.4064)
			(end 0.7874 0.4064)
			(stroke
				(width 0.1524)
				(type default)
			)
			(layer "F.SilkS")
		)
		(fp_line
			(start -0.7874 0.4064)
			(end -0.7874 -0.4064)
			(stroke
				(width 0.1524)
				(type default)
			)
			(layer "F.SilkS")
		)
		(fp_line
			(start -0.7874 -0.4064)
			(end 0.7874 -0.4064)
			(stroke
				(width 0.1524)
				(type default)
			)
			(layer "F.SilkS")
		)
		(fp_line
			(start 0.67945 0.3048)
			(end 0.120396 0.3048)
			(stroke
				(width 0.1)
				(type default)
			)
			(layer "F.Fab")
		)
		(fp_line
			(start 0.67945 -0.3048)
			(end 0.67945 0.3048)
			(stroke
				(width 0.1)
				(type default)
			)
			(layer "F.Fab")
		)
		(fp_line
			(start 0.12065 -0.2794)
			(end 0.12065 -0.3048)
			(stroke
				(width 0.1)
				(type default)
			)
			(layer "F.Fab")
		)
		(fp_line
			(start 0.12065 -0.3048)
			(end 0.67945 -0.3048)
			(stroke
				(width 0.1)
				(type default)
			)
			(layer "F.Fab")
		)
		(fp_line
			(start 0.120396 0.3048)
			(end 0.120396 0.2794)
			(stroke
				(width 0.1)
				(type default)
			)
			(layer "F.Fab")
		)
		(fp_line
			(start 0.120396 0.2794)
			(end -0.12065 0.2794)
			(stroke
				(width 0.1)
				(type default)
			)
			(layer "F.Fab")
		)
		(fp_line
			(start -0.12065 0.3048)
			(end -0.67945 0.3048)
			(stroke
				(width 0.1)
				(type default)
			)
			(layer "F.Fab")
		)
		(fp_line
			(start -0.12065 0.2794)
			(end -0.12065 0.3048)
			(stroke
				(width 0.1)
				(type default)
			)
			(layer "F.Fab")
		)
		(fp_line
			(start -0.12065 -0.2794)
			(end 0.12065 -0.2794)
			(stroke
				(width 0.1)
				(type default)
			)
			(layer "F.Fab")
		)
		(fp_line
			(start -0.12065 -0.305054)
			(end -0.12065 -0.2794)
			(stroke
				(width 0.1)
				(type default)
			)
			(layer "F.Fab")
		)
		(fp_line
			(start -0.67945 0.3048)
			(end -0.67945 -0.305054)
			(stroke
				(width 0.1)
				(type default)
			)
			(layer "F.Fab")
		)
		(fp_line
			(start -0.67945 -0.305054)
			(end -0.12065 -0.305054)
			(stroke
				(width 0.1)
				(type default)
			)
			(layer "F.Fab")
		)
		(pad "1" smd circle
			(at -0.40005 0 180)
			(size 0 0)
			(layers "F.Cu" "F.Mask" "F.Paste")
			(net "P3V3_E1S_VCC_0")
		)
		(pad "2" smd circle
			(at 0.40005 0 180)
			(size 0 0)
			(layers "F.Cu" "F.Mask" "F.Paste")
			(net "GND")
		)
	)
)
